(kicad_pcb
	(version 20260206)
	(generator "pcbnew")
	(generator_version "10.0")
	(general
		(thickness 1.6)
		(legacy_teardrops no)
	)
	(paper "A4")
	(title_block
		(title "Bryce Canyon_R.DPB_16317-1_OCP.brd")
		(comment 1 "Bryce Canyon / footprints 1707-1711 of 2099")
	)
	(layers
		(0 "F.Cu" signal "TOP")
		(4 "In1.Cu" signal "L2GND")
		(6 "In2.Cu" signal "L3")
		(8 "In3.Cu" signal "L4VCC")
		(10 "In4.Cu" signal "L5VCC")
		(12 "In5.Cu" signal "L6")
		(14 "In6.Cu" signal "L7GND")
		(2 "B.Cu" signal "BOTTOM")
		(9 "F.Adhes" user "F.Adhesive")
		(11 "B.Adhes" user "B.Adhesive")
		(13 "F.Paste" user "Package Geometry/Pastemask Top")
		(15 "B.Paste" user "Package Geometry/Pastemask Bottom")
		(5 "F.SilkS" user "Ref Des/Silkscreen Top")
		(7 "B.SilkS" user "Ref Des/Silkscreen Bottom")
		(1 "F.Mask" user "Board Geometry/Soldermask Top")
		(3 "B.Mask" user "Board Geometry/Soldermask Bottom")
		(17 "Dwgs.User" user "User.Drawings")
		(19 "Cmts.User" user "User.Comments")
		(21 "Eco1.User" user "User.Eco1")
		(23 "Eco2.User" user "User.Eco2")
		(25 "Edge.Cuts" user "Board Geometry/Outline")
		(27 "Margin" user)
		(31 "F.CrtYd" user "Package Geometry/Place Bound Top")
		(29 "B.CrtYd" user "Package Geometry/Place Bound Bottom")
		(35 "F.Fab" user "Ref Des/Assembly Top")
		(33 "B.Fab" user "Ref Des/Assembly Bottom")
	)
	(footprint ""
		(layer "F.Cu")
		(at 353.1616 -146.6342)
		(property "Reference" "C281"
			(at 0 0 0)
			(layer "F.SilkS")
			(hide yes)
			(effects
				(font
					(size 1.27 1.27)
				)
			)
		)
		(property "Value" "SCD01U50V2KX-1GP"
			(at 1.1811 -2.7051 0)
			(unlocked yes)
			(layer "F.Fab")
			(hide yes)
			(effects
				(font
					(size 1.016 1.016)
					(thickness 0.1524)
				)
			)
		)
		(property "Device Type" "C402H22"
			(at 1.1811 -4.2291 0)
			(unlocked yes)
			(layer "F.Fab")
			(hide yes)
			(effects
				(font
					(size 1.016 1.016)
					(thickness 0.1524)
				)
			)
		)
		(duplicate_pad_numbers_are_jumpers no)
		(fp_rect
			(start -0.4318 0.9525)
			(end 0.4318 -0.9525)
			(stroke
				(width 0)
				(type default)
			)
			(fill no)
			(layer "F.CrtYd")
		)
		(fp_rect
			(start -0.4318 0.9525)
			(end 0.4318 -0.9525)
			(stroke
				(width 0)
				(type default)
			)
			(fill no)
			(layer "F.Fab")
		)
		(pad "1" smd custom
			(at 0 -0.4445)
			(size 0.1524 0.1524)
			(layers "F.Cu" "F.Mask" "F.Paste")
			(net "HDD_PRSNT_19")
			(options
				(clearance outline)
				(anchor circle)
			)
			(primitives
				(gr_poly
					(pts
						(arc
							(start 0.3048 -0.2032)
							(mid 0.275042 -0.275042)
							(end 0.2032 -0.3048)
						)
						(arc
							(start -0.2032 -0.3048)
							(mid -0.275042 -0.275042)
							(end -0.3048 -0.2032)
						)
						(arc
							(start -0.3048 0.2032)
							(mid -0.275042 0.275042)
							(end -0.2032 0.3048)
						)
						(arc
							(start 0.2032 0.3048)
							(mid 0.275042 0.275042)
							(end 0.3048 0.2032)
						)
					)
					(width 0)
					(fill yes)
				)
			)
		)
		(pad "2" smd custom
			(at 0 0.4445)
			(size 0.1524 0.1524)
			(layers "F.Cu" "F.Mask" "F.Paste")
			(net "GND")
			(options
				(clearance outline)
				(anchor circle)
			)
			(primitives
				(gr_poly
					(pts
						(arc
							(start 0.3048 -0.2032)
							(mid 0.275042 -0.275042)
							(end 0.2032 -0.3048)
						)
						(arc
							(start -0.2032 -0.3048)
							(mid -0.275042 -0.275042)
							(end -0.3048 -0.2032)
						)
						(arc
							(start -0.3048 0.2032)
							(mid -0.275042 0.275042)
							(end -0.2032 0.3048)
						)
						(arc
							(start 0.2032 0.3048)
							(mid 0.275042 0.275042)
							(end 0.3048 0.2032)
						)
					)
					(width 0)
					(fill yes)
				)
			)
		)
	)
	(footprint ""
		(layer "F.Cu")
		(at 236.093 -194.01028 90)
		(property "Reference" "C16"
			(at 0 0 90)
			(layer "F.SilkS")
			(hide yes)
			(effects
				(font
					(size 1.27 1.27)
				)
			)
		)
		(property "Value" "SCD1U16V2KX-3GP"
			(at 1.1811 -2.7051 90)
			(unlocked yes)
			(layer "F.Fab")
			(hide yes)
			(effects
				(font
					(size 1.016 1.016)
					(thickness 0.1524)
				)
			)
		)
		(property "Device Type" "C402H22"
			(at 1.1811 -4.2291 90)
			(unlocked yes)
			(layer "F.Fab")
			(hide yes)
			(effects
				(font
					(size 1.016 1.016)
					(thickness 0.1524)
				)
			)
		)
		(duplicate_pad_numbers_are_jumpers no)
		(fp_rect
			(start -0.4318 0.9525)
			(end 0.4318 -0.9525)
			(stroke
				(width 0)
				(type default)
			)
			(fill no)
			(layer "F.CrtYd")
		)
		(fp_rect
			(start -0.4318 0.9525)
			(end 0.4318 -0.9525)
			(stroke
				(width 0)
				(type default)
			)
			(fill no)
			(layer "F.Fab")
		)
		(pad "1" smd custom
			(at 0 -0.4445 90)
			(size 0.1524 0.1524)
			(layers "F.Cu" "F.Mask" "F.Paste")
			(net "GPIO_VCC_U9")
			(options
				(clearance outline)
				(anchor circle)
			)
			(primitives
				(gr_poly
					(pts
						(arc
							(start 0.3048 -0.2032)
							(mid 0.275042 -0.275042)
							(end 0.2032 -0.3048)
						)
						(arc
							(start -0.2032 -0.3048)
							(mid -0.275042 -0.275042)
							(end -0.3048 -0.2032)
						)
						(arc
							(start -0.3048 0.2032)
							(mid -0.275042 0.275042)
							(end -0.2032 0.3048)
						)
						(arc
							(start 0.2032 0.3048)
							(mid 0.275042 0.275042)
							(end 0.3048 0.2032)
						)
					)
					(width 0)
					(fill yes)
				)
			)
		)
		(pad "2" smd custom
			(at 0 0.4445 90)
			(size 0.1524 0.1524)
			(layers "F.Cu" "F.Mask" "F.Paste")
			(net "GND")
			(options
				(clearance outline)
				(anchor circle)
			)
			(primitives
				(gr_poly
					(pts
						(arc
							(start 0.3048 -0.2032)
							(mid 0.275042 -0.275042)
							(end 0.2032 -0.3048)
						)
						(arc
							(start -0.2032 -0.3048)
							(mid -0.275042 -0.275042)
							(end -0.3048 -0.2032)
						)
						(arc
							(start -0.3048 0.2032)
							(mid -0.275042 0.275042)
							(end -0.2032 0.3048)
						)
						(arc
							(start 0.2032 0.3048)
							(mid 0.275042 0.275042)
							(end 0.3048 0.2032)
						)
					)
					(width 0)
					(fill yes)
				)
			)
		)
	)
	(footprint ""
		(layer "F.Cu")
		(at 445.60236 -244.884194 90)
		(property "Reference" "VIA21"
			(at 0 0 90)
			(layer "F.SilkS")
			(hide yes)
			(effects
				(font
					(size 1.27 1.27)
				)
			)
		)
		(property "Value" "100OHM-8L-2D36MM-L18-GP"
			(at 3.8989 0.5715 90)
			(unlocked yes)
			(layer "F.Fab")
			(hide yes)
			(effects
				(font
					(size 1.016 1.016)
					(thickness 0.1524)
				)
			)
		)
		(property "Device Type" "VIA-PCIE-4P-414097"
			(at 3.8989 -0.9525 90)
			(unlocked yes)
			(layer "F.Fab")
			(hide yes)
			(effects
				(font
					(size 1.016 1.016)
					(thickness 0.1524)
				)
			)
		)
		(duplicate_pad_numbers_are_jumpers no)
		(fp_rect
			(start -2.0701 0.4826)
			(end 2.0701 -0.4826)
			(stroke
				(width 0)
				(type default)
			)
			(fill no)
			(layer "F.CrtYd")
		)
		(fp_rect
			(start -2.0701 0.4826)
			(end 2.0701 -0.4826)
			(stroke
				(width 0)
				(type default)
			)
			(fill no)
			(layer "F.Fab")
		)
		(pad "1" thru_hole circle
			(at -1.5875 0 90)
			(size 0.508 0.508)
			(drill 0.254)
			(layers "*.Cu" "*.Mask")
			(remove_unused_layers no)
			(net "GND")
			(clearance 0.2286)
			(thermal_gap 0.2286)
		)
		(pad "2" thru_hole circle
			(at -0.5715 0 90)
			(size 0.508 0.508)
			(drill 0.254)
			(layers "*.Cu" "*.Mask")
			(remove_unused_layers no)
			(net "PHY_SCC_B_TO_DRV_B_10_DP")
			(clearance 0.2286)
			(thermal_gap 0.2286)
		)
		(pad "3" thru_hole circle
			(at 0.5715 0 90)
			(size 0.508 0.508)
			(drill 0.254)
			(layers "*.Cu" "*.Mask")
			(remove_unused_layers no)
			(net "PHY_SCC_B_TO_DRV_B_10_DN")
			(clearance 0.2286)
			(thermal_gap 0.2286)
		)
		(pad "4" thru_hole circle
			(at 1.5875 0 90)
			(size 0.508 0.508)
			(drill 0.254)
			(layers "*.Cu" "*.Mask")
			(remove_unused_layers no)
			(net "GND")
			(clearance 0.2286)
			(thermal_gap 0.2286)
		)
	)
	(footprint ""
		(layer "F.Cu")
		(at 147.599908 -379.899926 180)
		(property "Reference" "FAN2"
			(at 0 0 180)
			(layer "F.SilkS")
			(hide yes)
			(effects
				(font
					(size 1.27 1.27)
				)
			)
		)
		(property "Value" "MLX-CONN10D-7-GP"
			(at -15.641574 4.697984 180)
			(unlocked yes)
			(layer "F.Fab")
			(hide yes)
			(effects
				(font
					(size 1.016 1.016)
					(thickness 0.1524)
				)
			)
		)
		(property "Device Type" "15-24-6103"
			(at -15.641574 3.173984 180)
			(unlocked yes)
			(layer "F.Fab")
			(hide yes)
			(effects
				(font
					(size 1.016 1.016)
					(thickness 0.1524)
				)
			)
		)
		(duplicate_pad_numbers_are_jumpers no)
		(fp_line
			(start 14.0462 8.1534)
			(end -14.0462 8.1534)
			(stroke
				(width 0.1524)
				(type default)
			)
			(layer "F.SilkS")
		)
		(fp_line
			(start 14.0462 -6.4516)
			(end 14.0462 8.1534)
			(stroke
				(width 0.1524)
				(type default)
			)
			(layer "F.SilkS")
		)
		(fp_line
			(start 9.9314 -6.4516)
			(end 14.0462 -6.4516)
			(stroke
				(width 0.1524)
				(type default)
			)
			(layer "F.SilkS")
		)
		(fp_line
			(start 9.9314 -14.3256)
			(end 9.9314 -6.4516)
			(stroke
				(width 0.1524)
				(type default)
			)
			(layer "F.SilkS")
		)
		(fp_line
			(start -9.9314 -6.4516)
			(end -9.9314 -14.3256)
			(stroke
				(width 0.1524)
				(type default)
			)
			(layer "F.SilkS")
		)
		(fp_line
			(start -9.9314 -14.3256)
			(end 9.9314 -14.3256)
			(stroke
				(width 0.1524)
				(type default)
			)
			(layer "F.SilkS")
		)
		(fp_line
			(start -14.0462 8.1534)
			(end -14.0462 -6.4516)
			(stroke
				(width 0.1524)
				(type default)
			)
			(layer "F.SilkS")
		)
		(fp_line
			(start -14.0462 -6.4516)
			(end -9.9314 -6.4516)
			(stroke
				(width 0.1524)
				(type default)
			)
			(layer "F.SilkS")
		)
		(fp_circle
			(center 8.400034 -7.29996)
			(end 6.761734 -7.29996)
			(stroke
				(width 0.3048)
				(type default)
			)
			(fill no)
			(layer "F.SilkS")
		)
		(fp_circle
			(center 8.400034 -12.800076)
			(end 6.761734 -12.800076)
			(stroke
				(width 0.3048)
				(type default)
			)
			(fill no)
			(layer "F.SilkS")
		)
		(fp_circle
			(center 4.19989 -7.29996)
			(end 2.56159 -7.29996)
			(stroke
				(width 0.3048)
				(type default)
			)
			(fill no)
			(layer "F.SilkS")
		)
		(fp_circle
			(center 4.19989 -12.800076)
			(end 2.56159 -12.800076)
			(stroke
				(width 0.3048)
				(type default)
			)
			(fill no)
			(layer "F.SilkS")
		)
		(fp_circle
			(center 0 -7.29996)
			(end -1.6383 -7.29996)
			(stroke
				(width 0.3048)
				(type default)
			)
			(fill no)
			(layer "F.SilkS")
		)
		(fp_circle
			(center 0 -12.800076)
			(end -1.6383 -12.800076)
			(stroke
				(width 0.3048)
				(type default)
			)
			(fill no)
			(layer "F.SilkS")
		)
		(fp_circle
			(center -4.19989 -7.29996)
			(end -5.83819 -7.29996)
			(stroke
				(width 0.3048)
				(type default)
			)
			(fill no)
			(layer "F.SilkS")
		)
		(fp_circle
			(center -4.19989 -12.800076)
			(end -5.83819 -12.800076)
			(stroke
				(width 0.3048)
				(type default)
			)
			(fill no)
			(layer "F.SilkS")
		)
		(fp_circle
			(center -8.400034 -7.29996)
			(end -10.038334 -7.29996)
			(stroke
				(width 0.3048)
				(type default)
			)
			(fill no)
			(layer "F.SilkS")
		)
		(fp_circle
			(center -8.400034 -12.800076)
			(end -10.038334 -12.800076)
			(stroke
				(width 0.3048)
				(type default)
			)
			(fill no)
			(layer "F.SilkS")
		)
		(fp_poly
			(pts
				(xy -13.7922 7.8994) (xy -13.7922 -6.1976) (xy -9.2964 -6.1976) (xy -9.2964 -13.6906) (xy 9.2964 -13.6906)
				(xy 9.2964 -6.1976) (xy 13.7922 -6.1976) (xy 13.7922 7.8994)
			)
			(stroke
				(width 0)
				(type default)
			)
			(fill no)
			(layer "F.CrtYd")
		)
		(fp_poly
			(pts
				(xy -14.3002 8.4074) (xy -14.3002 -6.7056) (xy -10.1854 -6.7056) (xy -10.1854 -14.5796) (xy 10.1854 -14.5796)
				(xy 10.1854 -6.7056) (xy 14.3002 -6.7056) (xy 14.3002 -0.00635) (xy 13.7922 -0.00635) (xy 13.7922 -6.1976)
				(xy 9.2964 -6.1976) (xy 9.2964 -13.6906) (xy -9.2964 -13.6906) (xy -9.2964 -6.1976) (xy -13.7922 -6.1976)
				(xy -13.7922 7.8994) (xy 13.7922 7.8994) (xy 13.7922 0.00635) (xy 14.3002 0.00635) (xy 14.3002 8.4074)
			)
			(stroke
				(width 0)
				(type default)
			)
			(fill no)
			(layer "F.CrtYd")
		)
		(fp_poly
			(pts
				(xy -14.3002 8.4074) (xy -14.3002 -6.7056) (xy -10.1854 -6.7056) (xy -10.1854 -14.5796) (xy 10.1854 -14.5796)
				(xy 10.1854 -6.7056) (xy 14.3002 -6.7056) (xy 14.3002 8.4074)
			)
			(stroke
				(width 0)
				(type default)
			)
			(fill no)
			(layer "F.Fab")
		)
		(pad "" np_thru_hole circle
			(at -8.400034 0 180)
			(size 0.254 0.254)
			(drill 3.0226)
			(layers "*.Cu" "*.Mask")
			(clearance 1.7399)
			(thermal_gap 1.7399)
		)
		(pad "" np_thru_hole circle
			(at 8.400034 0 180)
			(size 0.254 0.254)
			(drill 3.0226)
			(layers "*.Cu" "*.Mask")
			(clearance 1.7399)
			(thermal_gap 1.7399)
		)
		(pad "1" thru_hole circle
			(at 8.400034 -7.29996 180)
			(size 2.5654 2.5654)
			(drill 1.8034)
			(layers "*.Cu" "*.Mask")
			(remove_unused_layers no)
			(net "FAN_1_TACH0")
			(clearance 0.127)
			(thermal_gap 0.127)
		)
		(pad "2" thru_hole circle
			(at 8.400034 -12.800076 180)
			(size 2.5654 2.5654)
			(drill 1.8034)
			(layers "*.Cu" "*.Mask")
			(remove_unused_layers no)
			(net "FAN_1_TACH1")
			(clearance 0.127)
			(thermal_gap 0.127)
		)
		(pad "3" thru_hole circle
			(at 4.19989 -7.29996 180)
			(size 2.5654 2.5654)
			(drill 1.8034)
			(layers "*.Cu" "*.Mask")
			(remove_unused_layers no)
			(net "FAN_1_PWM")
			(clearance 0.127)
			(thermal_gap 0.127)
		)
		(pad "4" thru_hole circle
			(at 4.19989 -12.800076 180)
			(size 2.5654 2.5654)
			(drill 1.8034)
			(layers "*.Cu" "*.Mask")
			(remove_unused_layers no)
			(net "FAN_1_PWM")
			(clearance 0.127)
			(thermal_gap 0.127)
		)
		(pad "5" thru_hole circle
			(at 0 -7.29996 180)
			(size 2.5654 2.5654)
			(drill 1.8034)
			(layers "*.Cu" "*.Mask")
			(remove_unused_layers no)
			(net "FAN_1_INS_N")
			(clearance 0.127)
			(thermal_gap 0.127)
		)
		(pad "6" thru_hole circle
			(at 0 -12.800076 180)
			(size 2.5654 2.5654)
			(drill 1.8034)
			(layers "*.Cu" "*.Mask")
			(remove_unused_layers no)
			(net "Net_1775")
			(clearance 0.127)
			(thermal_gap 0.127)
		)
		(pad "7" thru_hole circle
			(at -4.19989 -7.29996 180)
			(size 2.5654 2.5654)
			(drill 1.8034)
			(layers "*.Cu" "*.Mask")
			(remove_unused_layers no)
			(net "P12V_FAN1")
			(clearance 0.127)
			(thermal_gap 0.127)
		)
		(pad "8" thru_hole circle
			(at -4.19989 -12.800076 180)
			(size 2.5654 2.5654)
			(drill 1.8034)
			(layers "*.Cu" "*.Mask")
			(remove_unused_layers no)
			(net "P12V_FAN1")
			(clearance 0.127)
			(thermal_gap 0.127)
		)
		(pad "9" thru_hole circle
			(at -8.400034 -7.29996 180)
			(size 2.5654 2.5654)
			(drill 1.8034)
			(layers "*.Cu" "*.Mask")
			(remove_unused_layers no)
			(net "GND")
			(clearance 0.127)
			(thermal_gap 0.127)
		)
		(pad "10" thru_hole circle
			(at -8.400034 -12.800076 180)
			(size 2.5654 2.5654)
			(drill 1.8034)
			(layers "*.Cu" "*.Mask")
			(remove_unused_layers no)
			(net "GND")
			(clearance 0.127)
			(thermal_gap 0.127)
		)
		(zone
			(layers "F.Cu" "B.Cu" "In1.Cu" "In2.Cu" "In3.Cu" "In4.Cu" "In5.Cu" "In6.Cu")
			(hatch none 0.5)
			(connect_pads
				(clearance 0)
			)
			(min_thickness 0.25)
			(keepout
				(tracks not_allowed)
				(vias allowed)
				(pads allowed)
				(copperpour not_allowed)
				(footprints allowed)
			)
			(placement
				(enabled no)
				(sheetname "")
			)
			(fill
				(thermal_gap 0.5)
				(thermal_bridge_width 0.5)
				(island_removal_mode 0)
			)
			(polygon
				(pts
					(arc
						(start 141.015974 -379.899926)
						(mid 137.383774 -379.899926)
						(end 141.015974 -379.899926)
					)
				)
			)
		)
		(zone
			(layers "F.Cu" "B.Cu" "In1.Cu" "In2.Cu" "In3.Cu" "In4.Cu" "In5.Cu" "In6.Cu")
			(hatch none 0.5)
			(connect_pads
				(clearance 0)
			)
			(min_thickness 0.25)
			(keepout
				(tracks not_allowed)
				(vias allowed)
				(pads allowed)
				(copperpour not_allowed)
				(footprints allowed)
			)
			(placement
				(enabled no)
				(sheetname "")
			)
			(fill
				(thermal_gap 0.5)
				(thermal_bridge_width 0.5)
				(island_removal_mode 0)
			)
			(polygon
				(pts
					(arc
						(start 157.816042 -379.899926)
						(mid 154.183842 -379.899926)
						(end 157.816042 -379.899926)
					)
				)
			)
		)
	)
	(footprint ""
		(layer "F.Cu")
		(at 141.097 -255.524 90)
		(property "Reference" "C91"
			(at 0 0 90)
			(layer "F.SilkS")
			(hide yes)
			(effects
				(font
					(size 1.27 1.27)
				)
			)
		)
		(property "Value" "SCD033U25V2KX-GP"
			(at 1.1811 -2.7051 90)
			(unlocked yes)
			(layer "F.Fab")
			(hide yes)
			(effects
				(font
					(size 1.016 1.016)
					(thickness 0.1524)
				)
			)
		)
		(property "Device Type" "C402H22"
			(at 1.1811 -4.2291 90)
			(unlocked yes)
			(layer "F.Fab")
			(hide yes)
			(effects
				(font
					(size 1.016 1.016)
					(thickness 0.1524)
				)
			)
		)
		(duplicate_pad_numbers_are_jumpers no)
		(fp_rect
			(start -0.4318 0.9525)
			(end 0.4318 -0.9525)
			(stroke
				(width 0)
				(type default)
			)
			(fill no)
			(layer "F.CrtYd")
		)
		(fp_rect
			(start -0.4318 0.9525)
			(end 0.4318 -0.9525)
			(stroke
				(width 0)
				(type default)
			)
			(fill no)
			(layer "F.Fab")
		)
		(pad "1" smd custom
			(at 0 -0.4445 90)
			(size 0.1524 0.1524)
			(layers "F.Cu" "F.Mask" "F.Paste")
			(net "P12V_B")
			(options
				(clearance outline)
				(anchor circle)
			)
			(primitives
				(gr_poly
					(pts
						(arc
							(start 0.3048 -0.2032)
							(mid 0.275042 -0.275042)
							(end 0.2032 -0.3048)
						)
						(arc
							(start -0.2032 -0.3048)
							(mid -0.275042 -0.275042)
							(end -0.3048 -0.2032)
						)
						(arc
							(start -0.3048 0.2032)
							(mid -0.275042 0.275042)
							(end -0.2032 0.3048)
						)
						(arc
							(start 0.2032 0.3048)
							(mid 0.275042 0.275042)
							(end 0.3048 0.2032)
						)
					)
					(width 0)
					(fill yes)
				)
			)
		)
		(pad "2" smd custom
			(at 0 0.4445 90)
			(size 0.1524 0.1524)
			(layers "F.Cu" "F.Mask" "F.Paste")
			(net "SW_HDD_N4")
			(options
				(clearance outline)
				(anchor circle)
			)
			(primitives
				(gr_poly
					(pts
						(arc
							(start 0.3048 -0.2032)
							(mid 0.275042 -0.275042)
							(end 0.2032 -0.3048)
						)
						(arc
							(start -0.2032 -0.3048)
							(mid -0.275042 -0.275042)
							(end -0.3048 -0.2032)
						)
						(arc
							(start -0.3048 0.2032)
							(mid -0.275042 0.275042)
							(end -0.2032 0.3048)
						)
						(arc
							(start 0.2032 0.3048)
							(mid 0.275042 0.275042)
							(end 0.3048 0.2032)
						)
					)
					(width 0)
					(fill yes)
				)
			)
		)
	)
)
